# T6G (Grand Teton) — schematic netlist excerpt (pin names and nets, part order shuffled) for the footprints in the layout excerpt that follows; sources: Cadence DE-HDL packaged netlist, KiCad conversion of 04192023_DAF0TMB3IC0_F0TG_MB_C_brd_V02_OCP.brd

R189  Q_RES  0 5% CHIP  pkg 0402LF  page 82 : A = FM_BMC_TPM_PRES_N ; B = FM_BMC_TPM_PRES_N_R
C889  Q_CAP_DIFFBUS  DIFF BUS_0.22UF 6.3V 20% X6S  pkg C0201  page 64 : \1\ = P5E_CPU0_P3_TX_C_DP<6> ; \2\ = P5E_CPU0_P3_TX_DP<6>
R1905  Q_RES  1K 1% CHIP  pkg 0402LF  page 134 : A = P3V3_AUX ; B = OCP_SFF_PRSNT0_R_N

(kicad_pcb
	(version 20260206)
	(generator "pcbnew")
	(generator_version "10.0")
	(general
		(thickness 1.6)
		(legacy_teardrops no)
	)
	(paper "A4")
	(title_block
		(title "04192023_DAF0TMB3IC0_F0TG_MB_C_brd_V02_OCP.brd")
		(comment 1 "Grand Teton / footprints 4883-4885 of 8354")
	)
	(layers
		(0 "F.Cu" signal "TOP")
		(4 "In1.Cu" signal "GND")
		(6 "In2.Cu" signal "IN1")
		(8 "In3.Cu" signal "GND1")
		(10 "In4.Cu" signal "IN2")
		(12 "In5.Cu" signal "GND2")
		(14 "In6.Cu" signal "IN3")
		(16 "In7.Cu" signal "GND3")
		(18 "In8.Cu" signal "VCC")
		(20 "In9.Cu" signal "VCC1")
		(22 "In10.Cu" signal "GND4")
		(24 "In11.Cu" signal "IN4")
		(26 "In12.Cu" signal "GND5")
		(28 "In13.Cu" signal "IN5")
		(30 "In14.Cu" signal "GND6")
		(32 "In15.Cu" signal "IN6")
		(34 "In16.Cu" signal "GND7")
		(2 "B.Cu" signal "BOTTOM")
		(9 "F.Adhes" user "F.Adhesive")
		(11 "B.Adhes" user "B.Adhesive")
		(13 "F.Paste" user "Package Geometry/Pastemask Top")
		(15 "B.Paste" user "Package Geometry/Pastemask Bottom")
		(5 "F.SilkS" user "Ref Des/Silkscreen Top")
		(7 "B.SilkS" user "Ref Des/Silkscreen Bottom")
		(1 "F.Mask" user "Board Geometry/Soldermask Top")
		(3 "B.Mask" user "Board Geometry/Soldermask Bottom")
		(17 "Dwgs.User" user "User.Drawings")
		(19 "Cmts.User" user "User.Comments")
		(21 "Eco1.User" user "User.Eco1")
		(23 "Eco2.User" user "User.Eco2")
		(25 "Edge.Cuts" user "Board Geometry/Outline")
		(27 "Margin" user)
		(31 "F.CrtYd" user "Package Geometry/Place Bound Top")
		(29 "B.CrtYd" user "Package Geometry/Place Bound Bottom")
		(35 "F.Fab" user "Ref Des/Assembly Top")
		(33 "B.Fab" user "Ref Des/Assembly Bottom")
	)
	(footprint ""
		(layer "F.Cu")
		(at 453.719946 -108.059728)
		(property "Reference" "R1905"
			(at 0 0 0)
			(layer "F.SilkS")
			(hide yes)
			(effects
				(font
					(size 1.27 1.27)
				)
			)
		)
		(property "Value" ""
			(at 0 0 0)
			(layer "F.Fab")
			(effects
				(font
					(size 1.27 1.27)
				)
			)
		)
		(duplicate_pad_numbers_are_jumpers no)
		(fp_line
			(start -0.7874 -0.4064)
			(end 0.7874 -0.4064)
			(stroke
				(width 0.1524)
				(type default)
			)
			(layer "F.SilkS")
		)
		(fp_line
			(start -0.7874 0.4064)
			(end -0.7874 -0.4064)
			(stroke
				(width 0.1524)
				(type default)
			)
			(layer "F.SilkS")
		)
		(fp_line
			(start 0.7874 -0.4064)
			(end 0.7874 0.4064)
			(stroke
				(width 0.1524)
				(type default)
			)
			(layer "F.SilkS")
		)
		(fp_line
			(start 0.7874 0.4064)
			(end -0.7874 0.4064)
			(stroke
				(width 0.1524)
				(type default)
			)
			(layer "F.SilkS")
		)
		(fp_line
			(start -0.67945 -0.305054)
			(end -0.12065 -0.305054)
			(stroke
				(width 0.1)
				(type default)
			)
			(layer "F.Fab")
		)
		(fp_line
			(start -0.67945 0.3048)
			(end -0.67945 -0.305054)
			(stroke
				(width 0.1)
				(type default)
			)
			(layer "F.Fab")
		)
		(fp_line
			(start -0.12065 -0.305054)
			(end -0.12065 -0.2794)
			(stroke
				(width 0.1)
				(type default)
			)
			(layer "F.Fab")
		)
		(fp_line
			(start -0.12065 -0.2794)
			(end 0.12065 -0.2794)
			(stroke
				(width 0.1)
				(type default)
			)
			(layer "F.Fab")
		)
		(fp_line
			(start -0.12065 0.2794)
			(end -0.12065 0.3048)
			(stroke
				(width 0.1)
				(type default)
			)
			(layer "F.Fab")
		)
		(fp_line
			(start -0.12065 0.3048)
			(end -0.67945 0.3048)
			(stroke
				(width 0.1)
				(type default)
			)
			(layer "F.Fab")
		)
		(fp_line
			(start 0.120396 0.2794)
			(end -0.12065 0.2794)
			(stroke
				(width 0.1)
				(type default)
			)
			(layer "F.Fab")
		)
		(fp_line
			(start 0.120396 0.3048)
			(end 0.120396 0.2794)
			(stroke
				(width 0.1)
				(type default)
			)
			(layer "F.Fab")
		)
		(fp_line
			(start 0.12065 -0.3048)
			(end 0.67945 -0.3048)
			(stroke
				(width 0.1)
				(type default)
			)
			(layer "F.Fab")
		)
		(fp_line
			(start 0.12065 -0.2794)
			(end 0.12065 -0.3048)
			(stroke
				(width 0.1)
				(type default)
			)
			(layer "F.Fab")
		)
		(fp_line
			(start 0.67945 -0.3048)
			(end 0.67945 0.3048)
			(stroke
				(width 0.1)
				(type default)
			)
			(layer "F.Fab")
		)
		(fp_line
			(start 0.67945 0.3048)
			(end 0.120396 0.3048)
			(stroke
				(width 0.1)
				(type default)
			)
			(layer "F.Fab")
		)
		(pad "1" smd circle
			(at -0.40005 0)
			(size 0 0)
			(layers "F.Cu" "F.Mask" "F.Paste")
			(net "P3V3_AUX")
		)
		(pad "2" smd circle
			(at 0.40005 0)
			(size 0 0)
			(layers "F.Cu" "F.Mask" "F.Paste")
			(net "OCP_SFF_PRSNT0_R_N")
		)
	)
	(footprint ""
		(layer "F.Cu")
		(at 180.721 -100.294948 90)
		(property "Reference" "R189"
			(at 0 0 90)
			(layer "F.SilkS")
			(hide yes)
			(effects
				(font
					(size 1.27 1.27)
				)
			)
		)
		(property "Value" ""
			(at 0 0 90)
			(layer "F.Fab")
			(effects
				(font
					(size 1.27 1.27)
				)
			)
		)
		(duplicate_pad_numbers_are_jumpers no)
		(fp_line
			(start 0.7874 -0.4064)
			(end 0.7874 0.4064)
			(stroke
				(width 0.1524)
				(type default)
			)
			(layer "F.SilkS")
		)
		(fp_line
			(start -0.7874 -0.4064)
			(end 0.7874 -0.4064)
			(stroke
				(width 0.1524)
				(type default)
			)
			(layer "F.SilkS")
		)
		(fp_line
			(start 0.7874 0.4064)
			(end -0.7874 0.4064)
			(stroke
				(width 0.1524)
				(type default)
			)
			(layer "F.SilkS")
		)
		(fp_line
			(start -0.7874 0.4064)
			(end -0.7874 -0.4064)
			(stroke
				(width 0.1524)
				(type default)
			)
			(layer "F.SilkS")
		)
		(fp_line
			(start -0.12065 -0.305054)
			(end -0.12065 -0.2794)
			(stroke
				(width 0.1)
				(type default)
			)
			(layer "F.Fab")
		)
		(fp_line
			(start -0.67945 -0.305054)
			(end -0.12065 -0.305054)
			(stroke
				(width 0.1)
				(type default)
			)
			(layer "F.Fab")
		)
		(fp_line
			(start 0.67945 -0.3048)
			(end 0.67945 0.3048)
			(stroke
				(width 0.1)
				(type default)
			)
			(layer "F.Fab")
		)
		(fp_line
			(start 0.12065 -0.3048)
			(end 0.67945 -0.3048)
			(stroke
				(width 0.1)
				(type default)
			)
			(layer "F.Fab")
		)
		(fp_line
			(start 0.12065 -0.2794)
			(end 0.12065 -0.3048)
			(stroke
				(width 0.1)
				(type default)
			)
			(layer "F.Fab")
		)
		(fp_line
			(start -0.12065 -0.2794)
			(end 0.12065 -0.2794)
			(stroke
				(width 0.1)
				(type default)
			)
			(layer "F.Fab")
		)
		(fp_line
			(start 0.120396 0.2794)
			(end -0.12065 0.2794)
			(stroke
				(width 0.1)
				(type default)
			)
			(layer "F.Fab")
		)
		(fp_line
			(start -0.12065 0.2794)
			(end -0.12065 0.3048)
			(stroke
				(width 0.1)
				(type default)
			)
			(layer "F.Fab")
		)
		(fp_line
			(start 0.67945 0.3048)
			(end 0.120396 0.3048)
			(stroke
				(width 0.1)
				(type default)
			)
			(layer "F.Fab")
		)
		(fp_line
			(start 0.120396 0.3048)
			(end 0.120396 0.2794)
			(stroke
				(width 0.1)
				(type default)
			)
			(layer "F.Fab")
		)
		(fp_line
			(start -0.12065 0.3048)
			(end -0.67945 0.3048)
			(stroke
				(width 0.1)
				(type default)
			)
			(layer "F.Fab")
		)
		(fp_line
			(start -0.67945 0.3048)
			(end -0.67945 -0.305054)
			(stroke
				(width 0.1)
				(type default)
			)
			(layer "F.Fab")
		)
		(pad "1" smd circle
			(at -0.40005 0 90)
			(size 0 0)
			(layers "F.Cu" "F.Mask" "F.Paste")
			(net "FM_BMC_TPM_PRES_N")
		)
		(pad "2" smd circle
			(at 0.40005 0 90)
			(size 0 0)
			(layers "F.Cu" "F.Mask" "F.Paste")
			(net "FM_BMC_TPM_PRES_N_R")
		)
	)
	(footprint ""
		(layer "F.Cu")
		(at 374.598692 -378.95403 -90)
		(property "Reference" "C889"
			(at 0 0 270)
			(layer "F.SilkS")
			(hide yes)
			(effects
				(font
					(size 1.27 1.27)
				)
			)
		)
		(property "Value" ""
			(at 0 0 270)
			(layer "F.Fab")
			(effects
				(font
					(size 1.27 1.27)
				)
			)
		)
		(duplicate_pad_numbers_are_jumpers no)
		(fp_line
			(start -0.299974 0.150114)
			(end -0.299974 -0.150114)
			(stroke
				(width 0.1)
				(type default)
			)
			(layer "F.Fab")
		)
		(fp_line
			(start 0.299974 0.150114)
			(end -0.299974 0.150114)
			(stroke
				(width 0.1)
				(type default)
			)
			(layer "F.Fab")
		)
		(fp_line
			(start -0.299974 -0.150114)
			(end 0.299974 -0.150114)
			(stroke
				(width 0.1)
				(type default)
			)
			(layer "F.Fab")
		)
		(fp_line
			(start 0.299974 -0.150114)
			(end 0.299974 0.150114)
			(stroke
				(width 0.1)
				(type default)
			)
			(layer "F.Fab")
		)
		(pad "1" smd rect
			(at -0.2667 0 270)
			(size 0.3048 0.381)
			(layers "F.Cu" "F.Mask" "F.Paste")
			(net "P5E_CPU0_P3_TX_C_DP<6>")
		)
		(pad "2" smd rect
			(at 0.2667 0 270)
			(size 0.3048 0.381)
			(layers "F.Cu" "F.Mask" "F.Paste")
			(net "P5E_CPU0_P3_TX_DP<6>")
		)
	)
)
